FILE_TYPE = MACRO_DRAWING;
SET COLOR_WIRE YELLOW;
SET COLOR_PROP ORANGE;
SET COLOR_DOT WHITE;
SET COLOR_ARC YELLOW;
SET COLOR_BODY GREEN;
SET COLOR_NOTE PURPLE;
SET PROP_DISPLAY VALUE;
SET PAGE_NUMBER P447;
FORCEADD PT5161LRS..8
(-7575 3800);
FORCEPROP 1 LAST LOCATION U6016
J 0
(-7925 5425);
DISPLAY 0.723404 (-7925 5425);
PAINT GREEN (-7925 5425);
FORCEPROP 0 LAST $SEC 8
J 0
(-7925 5575);
DISPLAY 0.680851 (-7925 5575);
PAINT MONO (-7925 5575);
DISPLAY INVISIBLE (-7925 5575);
FORCEPROP 0 LAST CDS_SEC 8
J 0
(-7925 5575);
DISPLAY 0.680851 (-7925 5575);
DISPLAY INVISIBLE (-7925 5575);
FORCEPROP 0 LASTPIN (-7125 4950) $PN R35
J 0
(-7115 4960);
DISPLAY 0.680851 (-7115 4960);
PAINT MONO (-7115 4960);
FORCEPROP 0 LASTPIN (-7125 4600) $PN AB35
J 0
(-7115 4610);
DISPLAY 0.680851 (-7115 4610);
PAINT MONO (-7115 4610);
FORCEPROP 0 LASTPIN (-7125 4250) $PN AJ35
J 0
(-7115 4260);
DISPLAY 0.680851 (-7115 4260);
PAINT MONO (-7115 4260);
FORCEPROP 0 LASTPIN (-7125 3900) $PN AT35
J 0
(-7115 3910);
DISPLAY 0.680851 (-7115 3910);
PAINT MONO (-7115 3910);
FORCEPROP 0 LASTPIN (-7125 3550) $PN BC35
J 0
(-7115 3560);
DISPLAY 0.680851 (-7115 3560);
PAINT MONO (-7115 3560);
FORCEPROP 0 LASTPIN (-7125 3200) $PN BK35
J 0
(-7115 3210);
DISPLAY 0.680851 (-7115 3210);
PAINT MONO (-7115 3210);
FORCEPROP 0 LASTPIN (-7125 2850) $PN BU35
J 0
(-7115 2860);
DISPLAY 0.680851 (-7115 2860);
PAINT MONO (-7115 2860);
FORCEPROP 0 LASTPIN (-7125 2500) $PN CD35
J 0
(-7115 2510);
DISPLAY 0.680851 (-7115 2510);
PAINT MONO (-7115 2510);
FORCEPROP 0 LASTPIN (-7125 5050) $PN N34
J 0
(-7115 5060);
DISPLAY 0.680851 (-7115 5060);
PAINT MONO (-7115 5060);
FORCEPROP 0 LASTPIN (-7125 4700) $PN Y34
J 0
(-7115 4710);
DISPLAY 0.680851 (-7115 4710);
PAINT MONO (-7115 4710);
FORCEPROP 0 LASTPIN (-7125 4350) $PN AG34
J 0
(-7115 4360);
DISPLAY 0.680851 (-7115 4360);
PAINT MONO (-7115 4360);
FORCEPROP 0 LASTPIN (-7125 4000) $PN AP34
J 0
(-7115 4010);
DISPLAY 0.680851 (-7115 4010);
PAINT MONO (-7115 4010);
FORCEPROP 0 LASTPIN (-7125 3650) $PN BA34
J 0
(-7115 3660);
DISPLAY 0.680851 (-7115 3660);
PAINT MONO (-7115 3660);
FORCEPROP 0 LASTPIN (-7125 3300) $PN BH34
J 0
(-7115 3310);
DISPLAY 0.680851 (-7115 3310);
PAINT MONO (-7115 3310);
FORCEPROP 0 LASTPIN (-7125 2950) $PN BR34
J 0
(-7115 2960);
DISPLAY 0.680851 (-7115 2960);
PAINT MONO (-7115 2960);
FORCEPROP 0 LASTPIN (-7125 2600) $PN CB34
J 0
(-7115 2610);
DISPLAY 0.680851 (-7115 2610);
PAINT MONO (-7115 2610);
FORCEPROP 2 LAST VALUE PT5161LRS
J 0
(-7925 5475);
DISPLAY 0.680851 (-7925 5475);
FORCEPROP 2 LAST PART_TYPE SMLF
J 0
(-7925 5525);
DISPLAY 0.680851 (-7925 5525);
FORCEPROP 1 LAST MATERIAL IC
J 0
(-7925 5275);
DISPLAY 0.723404 (-7925 5275);
PAINT GREEN (-7925 5275);
FORCEPROP 1 LAST NEEDS_NO_SIZE TRUE
J 0
(-7575 3800);
DISPLAY 0.723404 (-7575 3800);
PAINT GREEN (-7575 3800);
DISPLAY INVISIBLE (-7575 3800);
FORCEPROP 1 LAST CDS_LMAN_SYM_OUTLINE -350,1450,300,-1400
J 0
(-7575 3800);
DISPLAY 0.468085 (-7575 3800);
PAINT GREEN (-7575 3800);
DISPLAY INVISIBLE (-7575 3800);
FORCEPROP 2 LAST CDS_LIB pure_quanta
J 0
(-7575 3800);
DISPLAY INVISIBLE (-7575 3800);
FORCEPROP 1 LAST PATH I1
J 0
(-7575 3800);
DISPLAY 0.723404 (-7575 3800);
PAINT GREEN (-7575 3800);
DISPLAY INVISIBLE (-7575 3800);
FORCEPROP 1 LAST PART_NUMBER AJ051610U03
J 0
(-7925 5350);
DISPLAY 0.723404 (-7925 5350);
PAINT GREEN (-7925 5350);
DISPLAY INVISIBLE (-7925 5350);
FORCEADD TAP..1
(-6350 3900);
FORCEPROP 3 LASTPIN (-6400 3900) SIG_NAME P5E_CPU1_P2_TX_C_DP<12>
J 0
(-6390 3910);
DISPLAY 0.659574 (-6390 3910);
PAINT MONO (-6390 3910);
DISPLAY INVISIBLE (-6390 3910);
FORCEPROP 1 LASTPIN (-6400 3900) BN 12
J 0
(-6412 3908);
DISPLAY 0.680851 (-6412 3908);
PAINT GREEN (-6412 3908);
FORCEPROP 2 LAST CDS_LIB standard
J 0
(-6350 3900);
DISPLAY INVISIBLE (-6350 3900);
FORCEPROP 1 LAST BODY_TYPE PLUMBING
J 0
(-6350 3950);
DISPLAY 0.872340 (-6350 3950);
PAINT GREEN (-6350 3950);
DISPLAY INVISIBLE (-6350 3950);
FORCEPROP 1 LAST HDL_TAP TRUE
J 0
(-6025 3775);
DISPLAY 0.872340 (-6025 3775);
DISPLAY INVISIBLE (-6025 3775);
FORCEPROP 1 LAST PATH I10
J 0
(-6352 3900);
DISPLAY 0.872340 (-6352 3900);
PAINT GREEN (-6352 3900);
DISPLAY INVISIBLE (-6352 3900);
FORCEADD TAP..1
(-6550 4000);
FORCEPROP 3 LASTPIN (-6600 4000) SIG_NAME P5E_CPU1_P2_TX_C_DN<12>
J 0
(-6590 4010);
DISPLAY 0.659574 (-6590 4010);
PAINT MONO (-6590 4010);
DISPLAY INVISIBLE (-6590 4010);
FORCEPROP 1 LASTPIN (-6600 4000) BN 12
J 0
(-6612 4008);
DISPLAY 0.680851 (-6612 4008);
PAINT GREEN (-6612 4008);
FORCEPROP 2 LAST CDS_LIB standard
J 0
(-6550 4000);
DISPLAY INVISIBLE (-6550 4000);
FORCEPROP 1 LAST BODY_TYPE PLUMBING
J 0
(-6550 4050);
DISPLAY 0.872340 (-6550 4050);
PAINT GREEN (-6550 4050);
DISPLAY INVISIBLE (-6550 4050);
FORCEPROP 1 LAST HDL_TAP TRUE
J 0
(-6225 3875);
DISPLAY 0.872340 (-6225 3875);
DISPLAY INVISIBLE (-6225 3875);
FORCEPROP 1 LAST PATH I11
J 0
(-6552 4000);
DISPLAY 0.872340 (-6552 4000);
PAINT GREEN (-6552 4000);
DISPLAY INVISIBLE (-6552 4000);
FORCEADD TAP..1
(-6550 4350);
FORCEPROP 3 LASTPIN (-6600 4350) SIG_NAME P5E_CPU1_P2_TX_C_DN<13>
J 0
(-6590 4360);
DISPLAY 0.659574 (-6590 4360);
PAINT MONO (-6590 4360);
DISPLAY INVISIBLE (-6590 4360);
FORCEPROP 1 LASTPIN (-6600 4350) BN 13
J 0
(-6612 4358);
DISPLAY 0.680851 (-6612 4358);
PAINT GREEN (-6612 4358);
FORCEPROP 2 LAST CDS_LIB standard
J 0
(-6550 4350);
DISPLAY INVISIBLE (-6550 4350);
FORCEPROP 1 LAST BODY_TYPE PLUMBING
J 0
(-6550 4400);
DISPLAY 0.872340 (-6550 4400);
PAINT GREEN (-6550 4400);
DISPLAY INVISIBLE (-6550 4400);
FORCEPROP 1 LAST HDL_TAP TRUE
J 0
(-6225 4225);
DISPLAY 0.872340 (-6225 4225);
DISPLAY INVISIBLE (-6225 4225);
FORCEPROP 1 LAST PATH I12
J 0
(-6552 4350);
DISPLAY 0.872340 (-6552 4350);
PAINT GREEN (-6552 4350);
DISPLAY INVISIBLE (-6552 4350);
FORCEADD TAP..1
(-6550 4700);
FORCEPROP 3 LASTPIN (-6600 4700) SIG_NAME P5E_CPU1_P2_TX_C_DN<14>
J 0
(-6590 4710);
DISPLAY 0.659574 (-6590 4710);
PAINT MONO (-6590 4710);
DISPLAY INVISIBLE (-6590 4710);
FORCEPROP 1 LASTPIN (-6600 4700) BN 14
J 0
(-6612 4708);
DISPLAY 0.680851 (-6612 4708);
PAINT GREEN (-6612 4708);
FORCEPROP 2 LAST CDS_LIB standard
J 0
(-6550 4700);
DISPLAY INVISIBLE (-6550 4700);
FORCEPROP 1 LAST BODY_TYPE PLUMBING
J 0
(-6550 4750);
DISPLAY 0.872340 (-6550 4750);
PAINT GREEN (-6550 4750);
DISPLAY INVISIBLE (-6550 4750);
FORCEPROP 1 LAST HDL_TAP TRUE
J 0
(-6225 4575);
DISPLAY 0.872340 (-6225 4575);
DISPLAY INVISIBLE (-6225 4575);
FORCEPROP 1 LAST PATH I13
J 0
(-6552 4700);
DISPLAY 0.872340 (-6552 4700);
PAINT GREEN (-6552 4700);
DISPLAY INVISIBLE (-6552 4700);
FORCEADD TAP..1
(-6350 4250);
FORCEPROP 3 LASTPIN (-6400 4250) SIG_NAME P5E_CPU1_P2_TX_C_DP<13>
J 0
(-6390 4260);
DISPLAY 0.659574 (-6390 4260);
PAINT MONO (-6390 4260);
DISPLAY INVISIBLE (-6390 4260);
FORCEPROP 1 LASTPIN (-6400 4250) BN 13
J 0
(-6412 4258);
DISPLAY 0.680851 (-6412 4258);
PAINT GREEN (-6412 4258);
FORCEPROP 2 LAST CDS_LIB standard
J 0
(-6350 4250);
DISPLAY INVISIBLE (-6350 4250);
FORCEPROP 1 LAST BODY_TYPE PLUMBING
J 0
(-6350 4300);
DISPLAY 0.872340 (-6350 4300);
PAINT GREEN (-6350 4300);
DISPLAY INVISIBLE (-6350 4300);
FORCEPROP 1 LAST HDL_TAP TRUE
J 0
(-6025 4125);
DISPLAY 0.872340 (-6025 4125);
DISPLAY INVISIBLE (-6025 4125);
FORCEPROP 1 LAST PATH I14
J 0
(-6352 4250);
DISPLAY 0.872340 (-6352 4250);
PAINT GREEN (-6352 4250);
DISPLAY INVISIBLE (-6352 4250);
FORCEADD TAP..1
(-6350 4600);
FORCEPROP 3 LASTPIN (-6400 4600) SIG_NAME P5E_CPU1_P2_TX_C_DP<14>
J 0
(-6390 4610);
DISPLAY 0.659574 (-6390 4610);
PAINT MONO (-6390 4610);
DISPLAY INVISIBLE (-6390 4610);
FORCEPROP 1 LASTPIN (-6400 4600) BN 14
J 0
(-6412 4608);
DISPLAY 0.680851 (-6412 4608);
PAINT GREEN (-6412 4608);
FORCEPROP 2 LAST CDS_LIB standard
J 0
(-6350 4600);
DISPLAY INVISIBLE (-6350 4600);
FORCEPROP 1 LAST BODY_TYPE PLUMBING
J 0
(-6350 4650);
DISPLAY 0.872340 (-6350 4650);
PAINT GREEN (-6350 4650);
DISPLAY INVISIBLE (-6350 4650);
FORCEPROP 1 LAST HDL_TAP TRUE
J 0
(-6025 4475);
DISPLAY 0.872340 (-6025 4475);
DISPLAY INVISIBLE (-6025 4475);
FORCEPROP 1 LAST PATH I15
J 0
(-6352 4600);
DISPLAY 0.872340 (-6352 4600);
PAINT GREEN (-6352 4600);
DISPLAY INVISIBLE (-6352 4600);
FORCEADD TAP..1
(-6350 4950);
FORCEPROP 3 LASTPIN (-6400 4950) SIG_NAME P5E_CPU1_P2_TX_C_DP<15>
J 0
(-6390 4960);
DISPLAY 0.659574 (-6390 4960);
PAINT MONO (-6390 4960);
DISPLAY INVISIBLE (-6390 4960);
FORCEPROP 1 LASTPIN (-6400 4950) BN 15
J 0
(-6412 4958);
DISPLAY 0.680851 (-6412 4958);
PAINT GREEN (-6412 4958);
FORCEPROP 2 LAST CDS_LIB standard
J 0
(-6350 4950);
DISPLAY INVISIBLE (-6350 4950);
FORCEPROP 1 LAST BODY_TYPE PLUMBING
J 0
(-6350 5000);
DISPLAY 0.872340 (-6350 5000);
PAINT GREEN (-6350 5000);
DISPLAY INVISIBLE (-6350 5000);
FORCEPROP 1 LAST HDL_TAP TRUE
J 0
(-6025 4825);
DISPLAY 0.872340 (-6025 4825);
DISPLAY INVISIBLE (-6025 4825);
FORCEPROP 1 LAST PATH I16
J 0
(-6352 4950);
DISPLAY 0.872340 (-6352 4950);
PAINT GREEN (-6352 4950);
DISPLAY INVISIBLE (-6352 4950);
FORCEADD TAP..1
(-6550 5050);
FORCEPROP 3 LASTPIN (-6600 5050) SIG_NAME P5E_CPU1_P2_TX_C_DN<15>
J 0
(-6590 5060);
DISPLAY 0.659574 (-6590 5060);
PAINT MONO (-6590 5060);
DISPLAY INVISIBLE (-6590 5060);
FORCEPROP 1 LASTPIN (-6600 5050) BN 15
J 0
(-6612 5058);
DISPLAY 0.680851 (-6612 5058);
PAINT GREEN (-6612 5058);
FORCEPROP 2 LAST CDS_LIB standard
J 0
(-6550 5050);
DISPLAY INVISIBLE (-6550 5050);
FORCEPROP 1 LAST BODY_TYPE PLUMBING
J 0
(-6550 5100);
DISPLAY 0.872340 (-6550 5100);
PAINT GREEN (-6550 5100);
DISPLAY INVISIBLE (-6550 5100);
FORCEPROP 1 LAST HDL_TAP TRUE
J 0
(-6225 4925);
DISPLAY 0.872340 (-6225 4925);
DISPLAY INVISIBLE (-6225 4925);
FORCEPROP 1 LAST PATH I17
J 0
(-6552 5050);
DISPLAY 0.872340 (-6552 5050);
PAINT GREEN (-6552 5050);
DISPLAY INVISIBLE (-6552 5050);
FORCEADD OFFPAGE..1
R 2
(-5350 4975);
FORCEPROP 2 LAST $XR0 66 
J 0
(-5164 4975);
DISPLAY 0.638298 (-5164 4975);
PAINT MONO (-5164 4975);
FORCEPROP 2 LAST CDS_LIB standard
J 0
(-5350 4975);
DISPLAY INVISIBLE (-5350 4975);
FORCEPROP 1 LAST OFFPAGE TRUE
J 2
(-5675 4850);
DISPLAY 0.872340 (-5675 4850);
DISPLAY INVISIBLE (-5675 4850);
FORCEPROP 1 LAST COMMENT_BODY TRUE
J 2
(-5475 4875);
DISPLAY 0.872340 (-5475 4875);
PAINT GREEN (-5475 4875);
DISPLAY INVISIBLE (-5475 4875);
FORCEPROP 2 LAST PATH I18
J 0
(-5175 5050);
DISPLAY 0.680851 (-5175 5050);
DISPLAY INVISIBLE (-5175 5050);
FORCEADD OFFPAGE..1
R 2
(-5350 5075);
FORCEPROP 2 LAST $XR0 66 
J 0
(-5164 5075);
DISPLAY 0.638298 (-5164 5075);
PAINT MONO (-5164 5075);
FORCEPROP 2 LAST CDS_LIB standard
J 2
(-5350 5075);
DISPLAY INVISIBLE (-5350 5075);
FORCEPROP 1 LAST OFFPAGE TRUE
J 2
(-5675 4950);
DISPLAY 0.872340 (-5675 4950);
DISPLAY INVISIBLE (-5675 4950);
FORCEPROP 1 LAST COMMENT_BODY TRUE
J 2
(-5475 4975);
DISPLAY 0.872340 (-5475 4975);
PAINT GREEN (-5475 4975);
DISPLAY INVISIBLE (-5475 4975);
FORCEPROP 2 LAST PATH I19
J 0
(-5175 5150);
DISPLAY 0.680851 (-5175 5150);
DISPLAY INVISIBLE (-5175 5150);
FORCEADD TAP..1
(-6550 2600);
FORCEPROP 3 LASTPIN (-6600 2600) SIG_NAME P5E_CPU1_P2_TX_C_DN<8>
J 0
(-6590 2610);
DISPLAY 0.659574 (-6590 2610);
PAINT MONO (-6590 2610);
DISPLAY INVISIBLE (-6590 2610);
FORCEPROP 1 LASTPIN (-6600 2600) BN 8
J 0
(-6612 2608);
DISPLAY 0.680851 (-6612 2608);
PAINT GREEN (-6612 2608);
FORCEPROP 2 LAST CDS_LIB standard
J 0
(-6550 2600);
DISPLAY INVISIBLE (-6550 2600);
FORCEPROP 1 LAST BODY_TYPE PLUMBING
J 0
(-6550 2650);
DISPLAY 0.872340 (-6550 2650);
PAINT GREEN (-6550 2650);
DISPLAY INVISIBLE (-6550 2650);
FORCEPROP 1 LAST HDL_TAP TRUE
J 0
(-6225 2475);
DISPLAY 0.872340 (-6225 2475);
DISPLAY INVISIBLE (-6225 2475);
FORCEPROP 1 LAST PATH I2
J 0
(-6552 2600);
DISPLAY 0.872340 (-6552 2600);
PAINT GREEN (-6552 2600);
DISPLAY INVISIBLE (-6552 2600);
FORCEADD TAP..1
(-1925 2550);
FORCEPROP 3 LASTPIN (-1975 2550) SIG_NAME P5E_CPU1_P2_TX_C_DN<0>
J 0
(-1965 2560);
DISPLAY 0.659574 (-1965 2560);
PAINT MONO (-1965 2560);
DISPLAY INVISIBLE (-1965 2560);
FORCEPROP 1 LASTPIN (-1975 2550) BN 0
J 0
(-1987 2558);
DISPLAY 0.680851 (-1987 2558);
PAINT GREEN (-1987 2558);
FORCEPROP 2 LAST CDS_LIB standard
J 0
(-1925 2550);
DISPLAY INVISIBLE (-1925 2550);
FORCEPROP 1 LAST BODY_TYPE PLUMBING
J 0
(-1925 2600);
DISPLAY 0.872340 (-1925 2600);
PAINT GREEN (-1925 2600);
DISPLAY INVISIBLE (-1925 2600);
FORCEPROP 1 LAST HDL_TAP TRUE
J 0
(-1600 2425);
DISPLAY 0.872340 (-1600 2425);
DISPLAY INVISIBLE (-1600 2425);
FORCEPROP 1 LAST PATH I20
J 0
(-1927 2550);
DISPLAY 0.872340 (-1927 2550);
PAINT GREEN (-1927 2550);
DISPLAY INVISIBLE (-1927 2550);
FORCEADD TAP..1
(-1925 2800);
FORCEPROP 3 LASTPIN (-1975 2800) SIG_NAME P5E_CPU1_P2_TX_C_DN<1>
J 0
(-1965 2810);
DISPLAY 0.659574 (-1965 2810);
PAINT MONO (-1965 2810);
DISPLAY INVISIBLE (-1965 2810);
FORCEPROP 1 LASTPIN (-1975 2800) BN 1
J 0
(-1987 2808);
DISPLAY 0.680851 (-1987 2808);
PAINT GREEN (-1987 2808);
FORCEPROP 2 LAST CDS_LIB standard
J 0
(-1925 2800);
DISPLAY INVISIBLE (-1925 2800);
FORCEPROP 1 LAST BODY_TYPE PLUMBING
J 0
(-1925 2850);
DISPLAY 0.872340 (-1925 2850);
PAINT GREEN (-1925 2850);
DISPLAY INVISIBLE (-1925 2850);
FORCEPROP 1 LAST HDL_TAP TRUE
J 0
(-1600 2675);
DISPLAY 0.872340 (-1600 2675);
DISPLAY INVISIBLE (-1600 2675);
FORCEPROP 1 LAST PATH I21
J 0
(-1927 2800);
DISPLAY 0.872340 (-1927 2800);
PAINT GREEN (-1927 2800);
DISPLAY INVISIBLE (-1927 2800);
FORCEADD TAP..1
(-1925 3250);
FORCEPROP 3 LASTPIN (-1975 3250) SIG_NAME P5E_CPU1_P2_TX_C_DN<2>
J 0
(-1965 3260);
DISPLAY 0.659574 (-1965 3260);
PAINT MONO (-1965 3260);
DISPLAY INVISIBLE (-1965 3260);
FORCEPROP 1 LASTPIN (-1975 3250) BN 2
J 0
(-1987 3258);
DISPLAY 0.680851 (-1987 3258);
PAINT GREEN (-1987 3258);
FORCEPROP 2 LAST CDS_LIB standard
J 0
(-1925 3250);
DISPLAY INVISIBLE (-1925 3250);
FORCEPROP 1 LAST BODY_TYPE PLUMBING
J 0
(-1925 3300);
DISPLAY 0.872340 (-1925 3300);
PAINT GREEN (-1925 3300);
DISPLAY INVISIBLE (-1925 3300);
FORCEPROP 1 LAST HDL_TAP TRUE
J 0
(-1600 3125);
DISPLAY 0.872340 (-1600 3125);
DISPLAY INVISIBLE (-1600 3125);
FORCEPROP 1 LAST PATH I22
J 0
(-1927 3250);
DISPLAY 0.872340 (-1927 3250);
PAINT GREEN (-1927 3250);
DISPLAY INVISIBLE (-1927 3250);
FORCEADD TAP..1
(-1925 3600);
FORCEPROP 3 LASTPIN (-1975 3600) SIG_NAME P5E_CPU1_P2_TX_C_DN<3>
J 0
(-1965 3610);
DISPLAY 0.659574 (-1965 3610);
PAINT MONO (-1965 3610);
DISPLAY INVISIBLE (-1965 3610);
FORCEPROP 1 LASTPIN (-1975 3600) BN 3
J 0
(-1987 3608);
DISPLAY 0.680851 (-1987 3608);
PAINT GREEN (-1987 3608);
FORCEPROP 2 LAST CDS_LIB standard
J 0
(-1925 3600);
DISPLAY INVISIBLE (-1925 3600);
FORCEPROP 1 LAST BODY_TYPE PLUMBING
J 0
(-1925 3650);
DISPLAY 0.872340 (-1925 3650);
PAINT GREEN (-1925 3650);
DISPLAY INVISIBLE (-1925 3650);
FORCEPROP 1 LAST HDL_TAP TRUE
J 0
(-1600 3475);
DISPLAY 0.872340 (-1600 3475);
DISPLAY INVISIBLE (-1600 3475);
FORCEPROP 1 LAST PATH I23
J 0
(-1927 3600);
DISPLAY 0.872340 (-1927 3600);
PAINT GREEN (-1927 3600);
DISPLAY INVISIBLE (-1927 3600);
FORCEADD TAP..1
(-1725 2450);
FORCEPROP 3 LASTPIN (-1775 2450) SIG_NAME P5E_CPU1_P2_TX_C_DP<0>
J 0
(-1765 2460);
DISPLAY 0.659574 (-1765 2460);
PAINT MONO (-1765 2460);
DISPLAY INVISIBLE (-1765 2460);
FORCEPROP 1 LASTPIN (-1775 2450) BN 0
J 0
(-1787 2458);
DISPLAY 0.680851 (-1787 2458);
PAINT GREEN (-1787 2458);
FORCEPROP 2 LAST CDS_LIB standard
J 0
(-1725 2450);
DISPLAY INVISIBLE (-1725 2450);
FORCEPROP 1 LAST BODY_TYPE PLUMBING
J 0
(-1725 2500);
DISPLAY 0.872340 (-1725 2500);
PAINT GREEN (-1725 2500);
DISPLAY INVISIBLE (-1725 2500);
FORCEPROP 1 LAST HDL_TAP TRUE
J 0
(-1400 2325);
DISPLAY 0.872340 (-1400 2325);
DISPLAY INVISIBLE (-1400 2325);
FORCEPROP 1 LAST PATH I24
J 0
(-1727 2450);
DISPLAY 0.872340 (-1727 2450);
PAINT GREEN (-1727 2450);
DISPLAY INVISIBLE (-1727 2450);
FORCEADD TAP..1
(-1725 2900);
FORCEPROP 3 LASTPIN (-1775 2900) SIG_NAME P5E_CPU1_P2_TX_C_DP<1>
J 0
(-1765 2910);
DISPLAY 0.659574 (-1765 2910);
PAINT MONO (-1765 2910);
DISPLAY INVISIBLE (-1765 2910);
FORCEPROP 1 LASTPIN (-1775 2900) BN 1
J 0
(-1787 2908);
DISPLAY 0.680851 (-1787 2908);
PAINT GREEN (-1787 2908);
FORCEPROP 2 LAST CDS_LIB standard
J 0
(-1725 2900);
DISPLAY INVISIBLE (-1725 2900);
FORCEPROP 1 LAST BODY_TYPE PLUMBING
J 0
(-1725 2950);
DISPLAY 0.872340 (-1725 2950);
PAINT GREEN (-1725 2950);
DISPLAY INVISIBLE (-1725 2950);
FORCEPROP 1 LAST HDL_TAP TRUE
J 0
(-1400 2775);
DISPLAY 0.872340 (-1400 2775);
DISPLAY INVISIBLE (-1400 2775);
FORCEPROP 1 LAST PATH I25
J 0
(-1727 2900);
DISPLAY 0.872340 (-1727 2900);
PAINT GREEN (-1727 2900);
DISPLAY INVISIBLE (-1727 2900);
FORCEADD TAP..1
(-1725 3150);
FORCEPROP 3 LASTPIN (-1775 3150) SIG_NAME P5E_CPU1_P2_TX_C_DP<2>
J 0
(-1765 3160);
DISPLAY 0.659574 (-1765 3160);
PAINT MONO (-1765 3160);
DISPLAY INVISIBLE (-1765 3160);
FORCEPROP 1 LASTPIN (-1775 3150) BN 2
J 0
(-1787 3158);
DISPLAY 0.680851 (-1787 3158);
PAINT GREEN (-1787 3158);
FORCEPROP 2 LAST CDS_LIB standard
J 0
(-1725 3150);
DISPLAY INVISIBLE (-1725 3150);
FORCEPROP 1 LAST BODY_TYPE PLUMBING
J 0
(-1725 3200);
DISPLAY 0.872340 (-1725 3200);
PAINT GREEN (-1725 3200);
DISPLAY INVISIBLE (-1725 3200);
FORCEPROP 1 LAST HDL_TAP TRUE
J 0
(-1400 3025);
DISPLAY 0.872340 (-1400 3025);
DISPLAY INVISIBLE (-1400 3025);
FORCEPROP 1 LAST PATH I26
J 0
(-1727 3150);
DISPLAY 0.872340 (-1727 3150);
PAINT GREEN (-1727 3150);
DISPLAY INVISIBLE (-1727 3150);
FORCEADD TAP..1
(-1725 3500);
FORCEPROP 3 LASTPIN (-1775 3500) SIG_NAME P5E_CPU1_P2_TX_C_DP<3>
J 0
(-1765 3510);
DISPLAY 0.659574 (-1765 3510);
PAINT MONO (-1765 3510);
DISPLAY INVISIBLE (-1765 3510);
FORCEPROP 1 LASTPIN (-1775 3500) BN 3
J 0
(-1787 3508);
DISPLAY 0.680851 (-1787 3508);
PAINT GREEN (-1787 3508);
FORCEPROP 2 LAST CDS_LIB standard
J 0
(-1725 3500);
DISPLAY INVISIBLE (-1725 3500);
FORCEPROP 1 LAST BODY_TYPE PLUMBING
J 0
(-1725 3550);
DISPLAY 0.872340 (-1725 3550);
PAINT GREEN (-1725 3550);
DISPLAY INVISIBLE (-1725 3550);
FORCEPROP 1 LAST HDL_TAP TRUE
J 0
(-1400 3375);
DISPLAY 0.872340 (-1400 3375);
DISPLAY INVISIBLE (-1400 3375);
FORCEPROP 1 LAST PATH I27
J 0
(-1727 3500);
DISPLAY 0.872340 (-1727 3500);
PAINT GREEN (-1727 3500);
DISPLAY INVISIBLE (-1727 3500);
FORCEADD TAP..1
(-1725 3850);
FORCEPROP 3 LASTPIN (-1775 3850) SIG_NAME P5E_CPU1_P2_TX_C_DP<4>
J 0
(-1765 3860);
DISPLAY 0.659574 (-1765 3860);
PAINT MONO (-1765 3860);
DISPLAY INVISIBLE (-1765 3860);
FORCEPROP 1 LASTPIN (-1775 3850) BN 4
J 0
(-1787 3858);
DISPLAY 0.680851 (-1787 3858);
PAINT GREEN (-1787 3858);
FORCEPROP 2 LAST CDS_LIB standard
J 0
(-1725 3850);
DISPLAY INVISIBLE (-1725 3850);
FORCEPROP 1 LAST BODY_TYPE PLUMBING
J 0
(-1725 3900);
DISPLAY 0.872340 (-1725 3900);
PAINT GREEN (-1725 3900);
DISPLAY INVISIBLE (-1725 3900);
FORCEPROP 1 LAST HDL_TAP TRUE
J 0
(-1400 3725);
DISPLAY 0.872340 (-1400 3725);
DISPLAY INVISIBLE (-1400 3725);
FORCEPROP 1 LAST PATH I28
J 0
(-1727 3850);
DISPLAY 0.872340 (-1727 3850);
PAINT GREEN (-1727 3850);
DISPLAY INVISIBLE (-1727 3850);
FORCEADD TAP..1
(-1925 3950);
FORCEPROP 3 LASTPIN (-1975 3950) SIG_NAME P5E_CPU1_P2_TX_C_DN<4>
J 0
(-1965 3960);
DISPLAY 0.659574 (-1965 3960);
PAINT MONO (-1965 3960);
DISPLAY INVISIBLE (-1965 3960);
FORCEPROP 1 LASTPIN (-1975 3950) BN 4
J 0
(-1987 3958);
DISPLAY 0.680851 (-1987 3958);
PAINT GREEN (-1987 3958);
FORCEPROP 2 LAST CDS_LIB standard
J 0
(-1925 3950);
DISPLAY INVISIBLE (-1925 3950);
FORCEPROP 1 LAST BODY_TYPE PLUMBING
J 0
(-1925 4000);
DISPLAY 0.872340 (-1925 4000);
PAINT GREEN (-1925 4000);
DISPLAY INVISIBLE (-1925 4000);
FORCEPROP 1 LAST HDL_TAP TRUE
J 0
(-1600 3825);
DISPLAY 0.872340 (-1600 3825);
DISPLAY INVISIBLE (-1600 3825);
FORCEPROP 1 LAST PATH I29
J 0
(-1927 3950);
DISPLAY 0.872340 (-1927 3950);
PAINT GREEN (-1927 3950);
DISPLAY INVISIBLE (-1927 3950);
FORCEADD TAP..1
(-6350 2500);
FORCEPROP 3 LASTPIN (-6400 2500) SIG_NAME P5E_CPU1_P2_TX_C_DP<8>
J 0
(-6390 2510);
DISPLAY 0.659574 (-6390 2510);
PAINT MONO (-6390 2510);
DISPLAY INVISIBLE (-6390 2510);
FORCEPROP 1 LASTPIN (-6400 2500) BN 8
J 0
(-6412 2508);
DISPLAY 0.680851 (-6412 2508);
PAINT GREEN (-6412 2508);
FORCEPROP 2 LAST CDS_LIB standard
J 0
(-6350 2500);
DISPLAY INVISIBLE (-6350 2500);
FORCEPROP 1 LAST BODY_TYPE PLUMBING
J 0
(-6350 2550);
DISPLAY 0.872340 (-6350 2550);
PAINT GREEN (-6350 2550);
DISPLAY INVISIBLE (-6350 2550);
FORCEPROP 1 LAST HDL_TAP TRUE
J 0
(-6025 2375);
DISPLAY 0.872340 (-6025 2375);
DISPLAY INVISIBLE (-6025 2375);
FORCEPROP 1 LAST PATH I3
J 0
(-6352 2500);
DISPLAY 0.872340 (-6352 2500);
PAINT GREEN (-6352 2500);
DISPLAY INVISIBLE (-6352 2500);
FORCEADD TAP..1
(-1925 4300);
FORCEPROP 3 LASTPIN (-1975 4300) SIG_NAME P5E_CPU1_P2_TX_C_DN<5>
J 0
(-1965 4310);
DISPLAY 0.659574 (-1965 4310);
PAINT MONO (-1965 4310);
DISPLAY INVISIBLE (-1965 4310);
FORCEPROP 1 LASTPIN (-1975 4300) BN 5
J 0
(-1987 4308);
DISPLAY 0.680851 (-1987 4308);
PAINT GREEN (-1987 4308);
FORCEPROP 2 LAST CDS_LIB standard
J 0
(-1925 4300);
DISPLAY INVISIBLE (-1925 4300);
FORCEPROP 1 LAST BODY_TYPE PLUMBING
J 0
(-1925 4350);
DISPLAY 0.872340 (-1925 4350);
PAINT GREEN (-1925 4350);
DISPLAY INVISIBLE (-1925 4350);
FORCEPROP 1 LAST HDL_TAP TRUE
J 0
(-1600 4175);
DISPLAY 0.872340 (-1600 4175);
DISPLAY INVISIBLE (-1600 4175);
FORCEPROP 1 LAST PATH I30
J 0
(-1927 4300);
DISPLAY 0.872340 (-1927 4300);
PAINT GREEN (-1927 4300);
DISPLAY INVISIBLE (-1927 4300);
FORCEADD TAP..1
(-1925 4650);
FORCEPROP 3 LASTPIN (-1975 4650) SIG_NAME P5E_CPU1_P2_TX_C_DN<6>
J 0
(-1965 4660);
DISPLAY 0.659574 (-1965 4660);
PAINT MONO (-1965 4660);
DISPLAY INVISIBLE (-1965 4660);
FORCEPROP 1 LASTPIN (-1975 4650) BN 6
J 0
(-1987 4658);
DISPLAY 0.680851 (-1987 4658);
PAINT GREEN (-1987 4658);
FORCEPROP 2 LAST CDS_LIB standard
J 0
(-1925 4650);
DISPLAY INVISIBLE (-1925 4650);
FORCEPROP 1 LAST BODY_TYPE PLUMBING
J 0
(-1925 4700);
DISPLAY 0.872340 (-1925 4700);
PAINT GREEN (-1925 4700);
DISPLAY INVISIBLE (-1925 4700);
FORCEPROP 1 LAST HDL_TAP TRUE
J 0
(-1600 4525);
DISPLAY 0.872340 (-1600 4525);
DISPLAY INVISIBLE (-1600 4525);
FORCEPROP 1 LAST PATH I31
J 0
(-1927 4650);
DISPLAY 0.872340 (-1927 4650);
PAINT GREEN (-1927 4650);
DISPLAY INVISIBLE (-1927 4650);
FORCEADD TAP..1
(-1925 5000);
FORCEPROP 3 LASTPIN (-1975 5000) SIG_NAME P5E_CPU1_P2_TX_C_DN<7>
J 0
(-1965 5010);
DISPLAY 0.659574 (-1965 5010);
PAINT MONO (-1965 5010);
DISPLAY INVISIBLE (-1965 5010);
FORCEPROP 1 LASTPIN (-1975 5000) BN 7
J 0
(-1987 5008);
DISPLAY 0.680851 (-1987 5008);
PAINT GREEN (-1987 5008);
FORCEPROP 2 LAST CDS_LIB standard
J 0
(-1925 5000);
DISPLAY INVISIBLE (-1925 5000);
FORCEPROP 1 LAST BODY_TYPE PLUMBING
J 0
(-1925 5050);
DISPLAY 0.872340 (-1925 5050);
PAINT GREEN (-1925 5050);
DISPLAY INVISIBLE (-1925 5050);
FORCEPROP 1 LAST HDL_TAP TRUE
J 0
(-1600 4875);
DISPLAY 0.872340 (-1600 4875);
DISPLAY INVISIBLE (-1600 4875);
FORCEPROP 1 LAST PATH I32
J 0
(-1927 5000);
DISPLAY 0.872340 (-1927 5000);
PAINT GREEN (-1927 5000);
DISPLAY INVISIBLE (-1927 5000);
FORCEADD TAP..1
(-1725 4200);
FORCEPROP 3 LASTPIN (-1775 4200) SIG_NAME P5E_CPU1_P2_TX_C_DP<5>
J 0
(-1765 4210);
DISPLAY 0.659574 (-1765 4210);
PAINT MONO (-1765 4210);
DISPLAY INVISIBLE (-1765 4210);
FORCEPROP 1 LASTPIN (-1775 4200) BN 5
J 0
(-1787 4208);
DISPLAY 0.680851 (-1787 4208);
PAINT GREEN (-1787 4208);
FORCEPROP 2 LAST CDS_LIB standard
J 0
(-1725 4200);
DISPLAY INVISIBLE (-1725 4200);
FORCEPROP 1 LAST BODY_TYPE PLUMBING
J 0
(-1725 4250);
DISPLAY 0.872340 (-1725 4250);
PAINT GREEN (-1725 4250);
DISPLAY INVISIBLE (-1725 4250);
FORCEPROP 1 LAST HDL_TAP TRUE
J 0
(-1400 4075);
DISPLAY 0.872340 (-1400 4075);
DISPLAY INVISIBLE (-1400 4075);
FORCEPROP 1 LAST PATH I33
J 0
(-1727 4200);
DISPLAY 0.872340 (-1727 4200);
PAINT GREEN (-1727 4200);
DISPLAY INVISIBLE (-1727 4200);
FORCEADD TAP..1
(-1725 4550);
FORCEPROP 3 LASTPIN (-1775 4550) SIG_NAME P5E_CPU1_P2_TX_C_DP<6>
J 0
(-1765 4560);
DISPLAY 0.659574 (-1765 4560);
PAINT MONO (-1765 4560);
DISPLAY INVISIBLE (-1765 4560);
FORCEPROP 1 LASTPIN (-1775 4550) BN 6
J 0
(-1787 4558);
DISPLAY 0.680851 (-1787 4558);
PAINT GREEN (-1787 4558);
FORCEPROP 2 LAST CDS_LIB standard
J 0
(-1725 4550);
DISPLAY INVISIBLE (-1725 4550);
FORCEPROP 1 LAST BODY_TYPE PLUMBING
J 0
(-1725 4600);
DISPLAY 0.872340 (-1725 4600);
PAINT GREEN (-1725 4600);
DISPLAY INVISIBLE (-1725 4600);
FORCEPROP 1 LAST HDL_TAP TRUE
J 0
(-1400 4425);
DISPLAY 0.872340 (-1400 4425);
DISPLAY INVISIBLE (-1400 4425);
FORCEPROP 1 LAST PATH I34
J 0
(-1727 4550);
DISPLAY 0.872340 (-1727 4550);
PAINT GREEN (-1727 4550);
DISPLAY INVISIBLE (-1727 4550);
FORCEADD TAP..1
(-1725 4900);
FORCEPROP 3 LASTPIN (-1775 4900) SIG_NAME P5E_CPU1_P2_TX_C_DP<7>
J 0
(-1765 4910);
DISPLAY 0.659574 (-1765 4910);
PAINT MONO (-1765 4910);
DISPLAY INVISIBLE (-1765 4910);
FORCEPROP 1 LASTPIN (-1775 4900) BN 7
J 0
(-1787 4908);
DISPLAY 0.680851 (-1787 4908);
PAINT GREEN (-1787 4908);
FORCEPROP 2 LAST CDS_LIB standard
J 0
(-1725 4900);
DISPLAY INVISIBLE (-1725 4900);
FORCEPROP 1 LAST BODY_TYPE PLUMBING
J 0
(-1725 4950);
DISPLAY 0.872340 (-1725 4950);
PAINT GREEN (-1725 4950);
DISPLAY INVISIBLE (-1725 4950);
FORCEPROP 1 LAST HDL_TAP TRUE
J 0
(-1400 4775);
DISPLAY 0.872340 (-1400 4775);
DISPLAY INVISIBLE (-1400 4775);
FORCEPROP 1 LAST PATH I35
J 0
(-1727 4900);
DISPLAY 0.872340 (-1727 4900);
PAINT GREEN (-1727 4900);
DISPLAY INVISIBLE (-1727 4900);
FORCEADD OFFPAGE..1
R 2
(-725 4925);
FORCEPROP 2 LAST $XR0 66 
J 0
(-539 4925);
DISPLAY 0.638298 (-539 4925);
PAINT MONO (-539 4925);
FORCEPROP 2 LAST CDS_LIB standard
J 0
(-725 4925);
DISPLAY INVISIBLE (-725 4925);
FORCEPROP 1 LAST OFFPAGE TRUE
J 2
(-1050 4800);
DISPLAY 0.872340 (-1050 4800);
DISPLAY INVISIBLE (-1050 4800);
FORCEPROP 1 LAST COMMENT_BODY TRUE
J 2
(-850 4825);
DISPLAY 0.872340 (-850 4825);
PAINT GREEN (-850 4825);
DISPLAY INVISIBLE (-850 4825);
FORCEPROP 2 LAST PATH I36
J 0
(-550 5000);
DISPLAY 0.680851 (-550 5000);
DISPLAY INVISIBLE (-550 5000);
FORCEADD OFFPAGE..1
R 2
(-725 5025);
FORCEPROP 2 LAST $XR0 66 
J 0
(-539 5025);
DISPLAY 0.638298 (-539 5025);
PAINT MONO (-539 5025);
FORCEPROP 2 LAST CDS_LIB standard
J 2
(-725 5025);
DISPLAY INVISIBLE (-725 5025);
FORCEPROP 1 LAST OFFPAGE TRUE
J 2
(-1050 4900);
DISPLAY 0.872340 (-1050 4900);
DISPLAY INVISIBLE (-1050 4900);
FORCEPROP 1 LAST COMMENT_BODY TRUE
J 2
(-850 4925);
DISPLAY 0.872340 (-850 4925);
PAINT GREEN (-850 4925);
DISPLAY INVISIBLE (-850 4925);
FORCEPROP 2 LAST PATH I37
J 0
(-550 5100);
DISPLAY 0.680851 (-550 5100);
DISPLAY INVISIBLE (-550 5100);
FORCEADD PT5161LRS..9
(-2950 3750);
FORCEPROP 1 LAST LOCATION U6016
J 0
(-3300 5375);
DISPLAY 0.723404 (-3300 5375);
PAINT GREEN (-3300 5375);
FORCEPROP 0 LAST $SEC 9
J 0
(-3300 5525);
DISPLAY 0.680851 (-3300 5525);
PAINT MONO (-3300 5525);
DISPLAY INVISIBLE (-3300 5525);
FORCEPROP 0 LAST CDS_SEC 9
J 0
(-3300 5525);
DISPLAY 0.680851 (-3300 5525);
DISPLAY INVISIBLE (-3300 5525);
FORCEPROP 0 LASTPIN (-2500 4900) $PN CL35
J 0
(-2490 4910);
DISPLAY 0.680851 (-2490 4910);
PAINT MONO (-2490 4910);
FORCEPROP 0 LASTPIN (-2500 4550) $PN CV35
J 0
(-2490 4560);
DISPLAY 0.680851 (-2490 4560);
PAINT MONO (-2490 4560);
FORCEPROP 0 LASTPIN (-2500 4200) $PN DE35
J 0
(-2490 4210);
DISPLAY 0.680851 (-2490 4210);
PAINT MONO (-2490 4210);
FORCEPROP 0 LASTPIN (-2500 3850) $PN DM35
J 0
(-2490 3860);
DISPLAY 0.680851 (-2490 3860);
PAINT MONO (-2490 3860);
FORCEPROP 0 LASTPIN (-2500 3500) $PN DW35
J 0
(-2490 3510);
DISPLAY 0.680851 (-2490 3510);
PAINT MONO (-2490 3510);
FORCEPROP 0 LASTPIN (-2500 3150) $PN EF35
J 0
(-2490 3160);
DISPLAY 0.680851 (-2490 3160);
PAINT MONO (-2490 3160);
FORCEPROP 0 LASTPIN (-2500 2800) $PN EN35
J 0
(-2490 2810);
DISPLAY 0.680851 (-2490 2810);
PAINT MONO (-2490 2810);
FORCEPROP 0 LASTPIN (-2500 2450) $PN EY35
J 0
(-2490 2460);
DISPLAY 0.680851 (-2490 2460);
PAINT MONO (-2490 2460);
FORCEPROP 0 LASTPIN (-2500 5000) $PN CJ34
J 0
(-2490 5010);
DISPLAY 0.680851 (-2490 5010);
PAINT MONO (-2490 5010);
FORCEPROP 0 LASTPIN (-2500 4650) $PN CT34
J 0
(-2490 4660);
DISPLAY 0.680851 (-2490 4660);
PAINT MONO (-2490 4660);
FORCEPROP 0 LASTPIN (-2500 4300) $PN DC34
J 0
(-2490 4310);
DISPLAY 0.680851 (-2490 4310);
PAINT MONO (-2490 4310);
FORCEPROP 0 LASTPIN (-2500 3950) $PN DK34
J 0
(-2490 3960);
DISPLAY 0.680851 (-2490 3960);
PAINT MONO (-2490 3960);
FORCEPROP 0 LASTPIN (-2500 3600) $PN DU34
J 0
(-2490 3610);
DISPLAY 0.680851 (-2490 3610);
PAINT MONO (-2490 3610);
FORCEPROP 0 LASTPIN (-2500 3250) $PN ED34
J 0
(-2490 3260);
DISPLAY 0.680851 (-2490 3260);
PAINT MONO (-2490 3260);
FORCEPROP 0 LASTPIN (-2500 2900) $PN EL34
J 0
(-2490 2910);
DISPLAY 0.680851 (-2490 2910);
PAINT MONO (-2490 2910);
FORCEPROP 0 LASTPIN (-2500 2550) $PN EV34
J 0
(-2490 2560);
DISPLAY 0.680851 (-2490 2560);
PAINT MONO (-2490 2560);
FORCEPROP 1 LAST MATERIAL IC
J 0
(-3300 5225);
DISPLAY 0.723404 (-3300 5225);
PAINT GREEN (-3300 5225);
FORCEPROP 2 LAST VALUE PT5161LRS
J 0
(-3300 5425);
DISPLAY 0.680851 (-3300 5425);
FORCEPROP 2 LAST PART_TYPE SMLF
J 0
(-3300 5475);
DISPLAY 0.680851 (-3300 5475);
FORCEPROP 2 LAST CDS_LIB pure_quanta
J 0
(-2950 3750);
DISPLAY INVISIBLE (-2950 3750);
FORCEPROP 1 LAST CDS_LMAN_SYM_OUTLINE -350,1450,300,-1400
J 0
(-2950 3750);
DISPLAY 0.468085 (-2950 3750);
PAINT GREEN (-2950 3750);
DISPLAY INVISIBLE (-2950 3750);
FORCEPROP 1 LAST NEEDS_NO_SIZE TRUE
J 0
(-2950 3750);
DISPLAY 0.723404 (-2950 3750);
PAINT GREEN (-2950 3750);
DISPLAY INVISIBLE (-2950 3750);
FORCEPROP 1 LAST PATH I38
J 0
(-2950 3750);
DISPLAY 0.723404 (-2950 3750);
PAINT GREEN (-2950 3750);
DISPLAY INVISIBLE (-2950 3750);
FORCEPROP 1 LAST PART_NUMBER AJ051610U03
J 0
(-3300 5300);
DISPLAY 0.723404 (-3300 5300);
PAINT GREEN (-3300 5300);
DISPLAY INVISIBLE (-3300 5300);
FORCEADD TAP..1
(-6350 2850);
FORCEPROP 3 LASTPIN (-6400 2850) SIG_NAME P5E_CPU1_P2_TX_C_DP<9>
J 0
(-6390 2860);
DISPLAY 0.659574 (-6390 2860);
PAINT MONO (-6390 2860);
DISPLAY INVISIBLE (-6390 2860);
FORCEPROP 1 LASTPIN (-6400 2850) BN 9
J 0
(-6412 2858);
DISPLAY 0.680851 (-6412 2858);
PAINT GREEN (-6412 2858);
FORCEPROP 2 LAST CDS_LIB standard
J 0
(-6350 2850);
DISPLAY INVISIBLE (-6350 2850);
FORCEPROP 1 LAST BODY_TYPE PLUMBING
J 0
(-6350 2900);
DISPLAY 0.872340 (-6350 2900);
PAINT GREEN (-6350 2900);
DISPLAY INVISIBLE (-6350 2900);
FORCEPROP 1 LAST HDL_TAP TRUE
J 0
(-6025 2725);
DISPLAY 0.872340 (-6025 2725);
DISPLAY INVISIBLE (-6025 2725);
FORCEPROP 1 LAST PATH I4
J 0
(-6352 2850);
DISPLAY 0.872340 (-6352 2850);
PAINT GREEN (-6352 2850);
DISPLAY INVISIBLE (-6352 2850);
FORCEADD TAP..1
(-6550 2950);
FORCEPROP 3 LASTPIN (-6600 2950) SIG_NAME P5E_CPU1_P2_TX_C_DN<9>
J 0
(-6590 2960);
DISPLAY 0.659574 (-6590 2960);
PAINT MONO (-6590 2960);
DISPLAY INVISIBLE (-6590 2960);
FORCEPROP 1 LASTPIN (-6600 2950) BN 9
J 0
(-6612 2958);
DISPLAY 0.680851 (-6612 2958);
PAINT GREEN (-6612 2958);
FORCEPROP 2 LAST CDS_LIB standard
J 0
(-6550 2950);
DISPLAY INVISIBLE (-6550 2950);
FORCEPROP 1 LAST BODY_TYPE PLUMBING
J 0
(-6550 3000);
DISPLAY 0.872340 (-6550 3000);
PAINT GREEN (-6550 3000);
DISPLAY INVISIBLE (-6550 3000);
FORCEPROP 1 LAST HDL_TAP TRUE
J 0
(-6225 2825);
DISPLAY 0.872340 (-6225 2825);
DISPLAY INVISIBLE (-6225 2825);
FORCEPROP 1 LAST PATH I5
J 0
(-6552 2950);
DISPLAY 0.872340 (-6552 2950);
PAINT GREEN (-6552 2950);
DISPLAY INVISIBLE (-6552 2950);
FORCEADD TAP..1
(-6550 3300);
FORCEPROP 3 LASTPIN (-6600 3300) SIG_NAME P5E_CPU1_P2_TX_C_DN<10>
J 0
(-6590 3310);
DISPLAY 0.659574 (-6590 3310);
PAINT MONO (-6590 3310);
DISPLAY INVISIBLE (-6590 3310);
FORCEPROP 1 LASTPIN (-6600 3300) BN 10
J 0
(-6612 3308);
DISPLAY 0.680851 (-6612 3308);
PAINT GREEN (-6612 3308);
FORCEPROP 2 LAST CDS_LIB standard
J 0
(-6550 3300);
DISPLAY INVISIBLE (-6550 3300);
FORCEPROP 1 LAST BODY_TYPE PLUMBING
J 0
(-6550 3350);
DISPLAY 0.872340 (-6550 3350);
PAINT GREEN (-6550 3350);
DISPLAY INVISIBLE (-6550 3350);
FORCEPROP 1 LAST HDL_TAP TRUE
J 0
(-6225 3175);
DISPLAY 0.872340 (-6225 3175);
DISPLAY INVISIBLE (-6225 3175);
FORCEPROP 1 LAST PATH I6
J 0
(-6552 3300);
DISPLAY 0.872340 (-6552 3300);
PAINT GREEN (-6552 3300);
DISPLAY INVISIBLE (-6552 3300);
FORCEADD TAP..1
(-6550 3650);
FORCEPROP 3 LASTPIN (-6600 3650) SIG_NAME P5E_CPU1_P2_TX_C_DN<11>
J 0
(-6590 3660);
DISPLAY 0.659574 (-6590 3660);
PAINT MONO (-6590 3660);
DISPLAY INVISIBLE (-6590 3660);
FORCEPROP 1 LASTPIN (-6600 3650) BN 11
J 0
(-6612 3658);
DISPLAY 0.680851 (-6612 3658);
PAINT GREEN (-6612 3658);
FORCEPROP 2 LAST CDS_LIB standard
J 0
(-6550 3650);
DISPLAY INVISIBLE (-6550 3650);
FORCEPROP 1 LAST BODY_TYPE PLUMBING
J 0
(-6550 3700);
DISPLAY 0.872340 (-6550 3700);
PAINT GREEN (-6550 3700);
DISPLAY INVISIBLE (-6550 3700);
FORCEPROP 1 LAST HDL_TAP TRUE
J 0
(-6225 3525);
DISPLAY 0.872340 (-6225 3525);
DISPLAY INVISIBLE (-6225 3525);
FORCEPROP 1 LAST PATH I7
J 0
(-6552 3650);
DISPLAY 0.872340 (-6552 3650);
PAINT GREEN (-6552 3650);
DISPLAY INVISIBLE (-6552 3650);
FORCEADD TAP..1
(-6350 3200);
FORCEPROP 3 LASTPIN (-6400 3200) SIG_NAME P5E_CPU1_P2_TX_C_DP<10>
J 0
(-6390 3210);
DISPLAY 0.659574 (-6390 3210);
PAINT MONO (-6390 3210);
DISPLAY INVISIBLE (-6390 3210);
FORCEPROP 1 LASTPIN (-6400 3200) BN 10
J 0
(-6412 3208);
DISPLAY 0.680851 (-6412 3208);
PAINT GREEN (-6412 3208);
FORCEPROP 2 LAST CDS_LIB standard
J 0
(-6350 3200);
DISPLAY INVISIBLE (-6350 3200);
FORCEPROP 1 LAST BODY_TYPE PLUMBING
J 0
(-6350 3250);
DISPLAY 0.872340 (-6350 3250);
PAINT GREEN (-6350 3250);
DISPLAY INVISIBLE (-6350 3250);
FORCEPROP 1 LAST HDL_TAP TRUE
J 0
(-6025 3075);
DISPLAY 0.872340 (-6025 3075);
DISPLAY INVISIBLE (-6025 3075);
FORCEPROP 1 LAST PATH I8
J 0
(-6352 3200);
DISPLAY 0.872340 (-6352 3200);
PAINT GREEN (-6352 3200);
DISPLAY INVISIBLE (-6352 3200);
FORCEADD TAP..1
(-6350 3550);
FORCEPROP 3 LASTPIN (-6400 3550) SIG_NAME P5E_CPU1_P2_TX_C_DP<11>
J 0
(-6390 3560);
DISPLAY 0.659574 (-6390 3560);
PAINT MONO (-6390 3560);
DISPLAY INVISIBLE (-6390 3560);
FORCEPROP 1 LASTPIN (-6400 3550) BN 11
J 0
(-6412 3558);
DISPLAY 0.680851 (-6412 3558);
PAINT GREEN (-6412 3558);
FORCEPROP 2 LAST CDS_LIB standard
J 0
(-6350 3550);
DISPLAY INVISIBLE (-6350 3550);
FORCEPROP 1 LAST BODY_TYPE PLUMBING
J 0
(-6350 3600);
DISPLAY 0.872340 (-6350 3600);
PAINT GREEN (-6350 3600);
DISPLAY INVISIBLE (-6350 3600);
FORCEPROP 1 LAST HDL_TAP TRUE
J 0
(-6025 3425);
DISPLAY 0.872340 (-6025 3425);
DISPLAY INVISIBLE (-6025 3425);
FORCEPROP 1 LAST PATH I9
J 0
(-6352 3550);
DISPLAY 0.872340 (-6352 3550);
PAINT GREEN (-6352 3550);
DISPLAY INVISIBLE (-6352 3550);
FORCEADD QUANTA_TITLE_BLOCK_C..1
(0 0);
FORCEPROP 0 LAST CDS_CON_LAST_MODIFIED Thu Sep 14 16:12:55 2023
J 0
(-1885 15);
DISPLAY INVISIBLE (-1885 15);
FORCEPROP 1 LAST CUSTOM_TXT_CDS <CON_LAST_MODIFIED>
J 0
(-1885 15);
DISPLAY 0.978723 (-1885 15);
FORCEPROP 2 LAST CUSTOM_TXT_CDS <XR_PAGE_TITLE>
J 0
(-7890 5250);
DISPLAY 0.638298 (-7890 5250);
PAINT PINK (-7890 5250);
DISPLAY INVISIBLE (-7890 5250);
FORCEPROP 1 LAST CUSTOM_TXT_CDS <NAME_2>
J 0
(-3175 50);
FORCEPROP 1 LAST CUSTOM_TXT_CDS <NAME_1>
J 0
(-3175 175);
FORCEPROP 1 LAST CUSTOM_TXT_CDS <Q_NUMBER>
J 0
(-1403 103);
DISPLAY 1.212766 (-1403 103);
FORCEPROP 1 LAST CUSTOM_TXT_CDS <Q_PROJ>
J 0
(-2382 102);
DISPLAY 1.212766 (-2382 102);
FORCEPROP 1 LAST CUSTOM_TXT_CDS <Q_REV>
J 0
(-184 103);
DISPLAY 1.212766 (-184 103);
FORCEPROP 1 LAST CUSTOM_TXT_CDS <CON_PAGE_NUM> OF <CON_TOTAL_PAGES>
J 0
(-446 18);
DISPLAY 0.978723 (-446 18);
FORCEPROP 1 LAST Q_TITLE RETIMER_CPU1_P2(1)
J 0
(-9366 26);
DISPLAY 2.446809 (-9366 26);
PAINT GREEN (-9366 26);
FORCEPROP 2 LAST PAGE_BORDER TRUE
J 0
(-7890 5250);
DISPLAY 0.638298 (-7890 5250);
PAINT PINK (-7890 5250);
DISPLAY INVISIBLE (-7890 5250);
FORCEPROP 1 LAST CDS_LMAN_SYM_OUTLINE -9475,6775,100,-125
J 0
(0 0);
DISPLAY 0.468085 (0 0);
PAINT GREEN (0 0);
DISPLAY INVISIBLE (0 0);
FORCEPROP 2 LAST CDS_LIB pure_quanta
J 0
(0 0);
DISPLAY INVISIBLE (0 0);
FORCEPROP 2 LAST CDS_XR_PAGE_TITLE CR-339 : @T6G_MB_LIB.T6G(SCH_1):PAGE339
J 0
(-7890 5250);
DISPLAY 0.638298 (-7890 5250);
PAINT PINK (-7890 5250);
DISPLAY INVISIBLE (-7890 5250);
FORCEPROP 1 LAST Q_DEPT BU9
J 1
(-3763 49);
DISPLAY 1.957447 (-3763 49);
PAINT GREEN (-3763 49);
DISPLAY INVISIBLE (-3763 49);
FORCEPROP 1 LAST COMMENT_BODY TRUE
J 0
(12 -13);
DISPLAY 0.978723 (12 -13);
PAINT GREEN (12 -13);
DISPLAY INVISIBLE (12 -13);
WIRE 17 -1 (-1875 4675)(-1875 4325);
WIRE 17 -1 (-1875 5025)(-1875 4675);
WIRE 17 -1 (-1875 4325)(-1875 3975);
WIRE 17 -1 (-1875 3625)(-1875 3975);
WIRE 17 -1 (-1875 5025)(-775 5025);
FORCEPROP 2 LAST SIG_NAME P5E_CPU1_P2_TX_C_DN<7:0>
J 0
(-1610 5035);
DISPLAY 0.680851 (-1610 5035);
PAINT WHITE (-1610 5035);
WIRE 17 -1 (-1675 2925)(-1675 2475);
WIRE 17 -1 (-1675 3175)(-1675 2925);
WIRE 17 -1 (-1675 3525)(-1675 3175);
WIRE 17 -1 (-1675 3525)(-1675 3875);
WIRE 17 -1 (-1675 4225)(-1675 3875);
WIRE 17 -1 (-1675 4575)(-1675 4225);
WIRE 17 -1 (-1675 4925)(-1675 4575);
WIRE 17 -1 (-1675 4925)(-775 4925);
FORCEPROP 2 LAST SIG_NAME P5E_CPU1_P2_TX_C_DP<7:0>
J 0
(-1610 4935);
DISPLAY 0.680851 (-1610 4935);
PAINT WHITE (-1610 4935);
WIRE 17 -1 (-6300 2875)(-6300 2525);
WIRE 17 -1 (-6300 3225)(-6300 2875);
WIRE 17 -1 (-6300 3575)(-6300 3225);
WIRE 17 -1 (-6300 3575)(-6300 3925);
WIRE 17 -1 (-6300 4275)(-6300 3925);
WIRE 17 -1 (-6300 4625)(-6300 4275);
WIRE 17 -1 (-6300 4975)(-6300 4625);
WIRE 17 -1 (-6300 4975)(-5400 4975);
FORCEPROP 2 LAST SIG_NAME P5E_CPU1_P2_TX_C_DP<15:8>
J 0
(-6235 4985);
DISPLAY 0.680851 (-6235 4985);
PAINT WHITE (-6235 4985);
WIRE 17 -1 (-6500 5075)(-6500 4725);
WIRE 17 -1 (-6500 5075)(-5400 5075);
FORCEPROP 2 LAST SIG_NAME P5E_CPU1_P2_TX_C_DN<15:8>
J 0
(-6235 5085);
DISPLAY 0.680851 (-6235 5085);
PAINT WHITE (-6235 5085);
WIRE 17 -1 (-6500 3675)(-6500 4025);
WIRE 17 -1 (-6500 3675)(-6500 3325);
WIRE 17 -1 (-6500 4375)(-6500 4025);
WIRE 17 -1 (-6500 4725)(-6500 4375);
WIRE 17 -1 (-6500 3325)(-6500 2975);
WIRE 17 -1 (-6500 2975)(-6500 2625);
WIRE 17 -1 (-1875 3625)(-1875 3275);
WIRE 17 -1 (-1875 3275)(-1875 2825);
WIRE 17 -1 (-1875 2825)(-1875 2575);
WIRE 16 -1 (-2500 3150)(-1775 3150);
WIRE 16 -1 (-2500 2900)(-1775 2900);
WIRE 16 -1 (-1975 2800)(-2500 2800);
WIRE 16 -1 (-2500 3250)(-1975 3250);
WIRE 16 -1 (-2500 2550)(-1975 2550);
WIRE 16 -1 (-2500 4200)(-1775 4200);
WIRE 16 -1 (-2500 4550)(-1775 4550);
WIRE 16 -1 (-2500 4650)(-1975 4650);
WIRE 16 -1 (-2500 4900)(-1775 4900);
WIRE 16 -1 (-2500 5000)(-1975 5000);
WIRE 16 -1 (-7125 5050)(-6600 5050);
WIRE 16 -1 (-7125 4600)(-6400 4600);
WIRE 16 -1 (-2500 3950)(-1975 3950);
WIRE 16 -1 (-2500 3850)(-1775 3850);
WIRE 16 -1 (-2500 3600)(-1975 3600);
WIRE 16 -1 (-7125 3900)(-6400 3900);
WIRE 16 -1 (-7125 3300)(-6600 3300);
WIRE 16 -1 (-7125 3200)(-6400 3200);
WIRE 16 -1 (-7125 2950)(-6600 2950);
WIRE 16 -1 (-7125 2850)(-6400 2850);
WIRE 16 -1 (-7125 4350)(-6600 4350);
WIRE 16 -1 (-7125 4950)(-6400 4950);
WIRE 16 -1 (-7125 4000)(-6600 4000);
WIRE 16 -1 (-7125 2600)(-6600 2600);
WIRE 16 -1 (-7125 3550)(-6400 3550);
WIRE 16 -1 (-7125 3650)(-6600 3650);
WIRE 16 -1 (-7125 4250)(-6400 4250);
WIRE 16 -1 (-7125 4700)(-6600 4700);
WIRE 16 -1 (-7125 2500)(-6400 2500);
WIRE 16 -1 (-2500 3500)(-1775 3500);
WIRE 16 -1 (-2500 2450)(-1775 2450);
WIRE 16 -1 (-2500 4300)(-1975 4300);
FORCENOTE
P/N SWAP
(-6200 3575) 0;
DISPLAY LEFT (-6200 3575);
DISPLAY 1.021277 (-6200 3575);
FORCENOTE
P/N SWAP
(-6225 2550) 0;
DISPLAY LEFT (-6225 2550);
DISPLAY 1.021277 (-6225 2550);
FORCENOTE
P/N SWAP
(-6200 2875) 0;
DISPLAY LEFT (-6200 2875);
DISPLAY 1.021277 (-6200 2875);
FORCENOTE
P/N SWAP
(-1525 4550) 0;
DISPLAY LEFT (-1525 4550);
DISPLAY 1.021277 (-1525 4550);
FORCENOTE
P/N SWAP
(-1525 4825) 0;
DISPLAY LEFT (-1525 4825);
DISPLAY 1.021277 (-1525 4825);
FORCENOTE
P/N SWAP
(-1525 4275) 0;
DISPLAY LEFT (-1525 4275);
DISPLAY 1.021277 (-1525 4275);
FORCENOTE
P/N SWAP
(-1525 3875) 0;
DISPLAY LEFT (-1525 3875);
DISPLAY 1.021277 (-1525 3875);
FORCENOTE
P/N SWAP
(-1550 3525) 0;
DISPLAY LEFT (-1550 3525);
DISPLAY 1.021277 (-1550 3525);
FORCENOTE
P/N SWAP
(-1550 3175) 0;
DISPLAY LEFT (-1550 3175);
DISPLAY 1.021277 (-1550 3175);
FORCENOTE
P/N SWAP
(-1575 2500) 0;
DISPLAY LEFT (-1575 2500);
DISPLAY 1.021277 (-1575 2500);
FORCENOTE
P/N SWAP
(-6200 3225) 0;
DISPLAY LEFT (-6200 3225);
DISPLAY 1.021277 (-6200 3225);
FORCENOTE
P/N SWAP
(-6175 3925) 0;
DISPLAY LEFT (-6175 3925);
DISPLAY 1.021277 (-6175 3925);
FORCENOTE
P/N SWAP
(-6175 4325) 0;
DISPLAY LEFT (-6175 4325);
DISPLAY 1.021277 (-6175 4325);
FORCENOTE
P/N SWAP
(-6175 4875) 0;
DISPLAY LEFT (-6175 4875);
DISPLAY 1.021277 (-6175 4875);
FORCENOTE
P/N SWAP
(-6175 4600) 0;
DISPLAY LEFT (-6175 4600);
DISPLAY 1.021277 (-6175 4600);
FORCENOTE
P5E_CPU1_P2_TX_C_DP/DN<0-15> LANE REVERSAL
(-8950 6200) 0;
DISPLAY LEFT (-8950 6200);
DISPLAY 2.000000 (-8950 6200);
FORCENOTE
CPU TO RETIMER
(-3400 1650) 0;
DISPLAY LEFT (-3400 1650);
DISPLAY 3.148936 (-3400 1650);
FORCENOTE
CPU TO RETIMER
(-8000 1650) 0;
DISPLAY LEFT (-8000 1650);
DISPLAY 3.148936 (-8000 1650);
QUIT
